(kicad_pcb
	(version 20241229)
	(generator "pcbnew")
	(generator_version "9.0")
	(general
		(thickness 1.62)
		(legacy_teardrops no)
	)
	(paper "A3")
	(title_block
		(title "COM Express 7 Baseboard")
		(date "2025-02-04")
		(rev "1.1.2")
		(company "Antmicro Ltd")
		(comment 1 "www.antmicro.com")
		(comment 9 "footprints 636-641 of 802")
	)
	(layers
		(0 "F.Cu" signal)
		(4 "In1.Cu" signal)
		(6 "In2.Cu" signal)
		(8 "In3.Cu" signal)
		(10 "In4.Cu" signal)
		(12 "In5.Cu" signal)
		(14 "In6.Cu" signal)
		(2 "B.Cu" signal)
		(9 "F.Adhes" user "F.Adhesive")
		(11 "B.Adhes" user "B.Adhesive")
		(13 "F.Paste" user)
		(15 "B.Paste" user)
		(5 "F.SilkS" user "F.Silkscreen")
		(7 "B.SilkS" user "B.Silkscreen")
		(1 "F.Mask" user)
		(3 "B.Mask" user)
		(17 "Dwgs.User" user "User.Drawings")
		(19 "Cmts.User" user "User.Comments")
		(21 "Eco1.User" user "User.Eco1")
		(23 "Eco2.User" user "User.Eco2")
		(25 "Edge.Cuts" user)
		(27 "Margin" user)
		(31 "F.CrtYd" user "F.Courtyard")
		(29 "B.CrtYd" user "B.Courtyard")
		(35 "F.Fab" user)
		(33 "B.Fab" user)
	)
	(footprint "antmicro-footprints:C_0402_1005Metric"
		(layer "B.Cu")
		(at 137 163.76)
		(descr "Capacitor SMD 0402")
		(tags "capacitor SMD 0402")
		(property "Reference" "C27"
			(at -3.05 0.45 0)
			(layer "B.SilkS")
			(effects
				(font
					(size 0.7 0.7)
					(thickness 0.15)
				)
				(justify right bottom mirror)
			)
		)
		(property "Value" "C_100n_0402"
			(at -1.022927 -2.155213 0)
			(layer "B.Fab")
			(effects
				(font
					(size 0.7 0.7)
					(thickness 0.15)
				)
				(justify right bottom mirror)
			)
		)
		(property "Datasheet" "https://www.murata.com/products/productdetail?partno=GRM155R61H104KE14%23"
			(at 0 0 0)
			(layer "F.Fab")
			(hide yes)
			(effects
				(font
					(size 1.27 1.27)
					(thickness 0.15)
				)
			)
		)
		(property "Author" "Antmicro"
			(at 0 0 0)
			(layer "B.Fab")
			(hide yes)
			(effects
				(font
					(size 1 1)
					(thickness 0.15)
				)
				(justify mirror)
			)
		)
		(property "Dielectric" "X5R"
			(at 0 0 0)
			(layer "B.Fab")
			(hide yes)
			(effects
				(font
					(size 1 1)
					(thickness 0.15)
				)
				(justify mirror)
			)
		)
		(property "License" "Apache-2.0"
			(at 0 0 0)
			(layer "B.Fab")
			(hide yes)
			(effects
				(font
					(size 1 1)
					(thickness 0.15)
				)
				(justify mirror)
			)
		)
		(property "MPN" "GRM155R61H104KE14D"
			(at 0 0 0)
			(layer "B.Fab")
			(hide yes)
			(effects
				(font
					(size 1 1)
					(thickness 0.15)
				)
				(justify mirror)
			)
		)
		(property "Manufacturer" "Murata"
			(at 0 0 0)
			(layer "B.Fab")
			(hide yes)
			(effects
				(font
					(size 1 1)
					(thickness 0.15)
				)
				(justify mirror)
			)
		)
		(property "Public" "False"
			(at 0 0 0)
			(layer "B.Fab")
			(hide yes)
			(effects
				(font
					(size 1 1)
					(thickness 0.15)
				)
				(justify mirror)
			)
		)
		(property "Val" "100n"
			(at 0 0 0)
			(layer "B.Fab")
			(hide yes)
			(effects
				(font
					(size 1 1)
					(thickness 0.15)
				)
				(justify mirror)
			)
		)
		(property "Voltage" "50V"
			(at 0 0 0)
			(layer "B.Fab")
			(hide yes)
			(effects
				(font
					(size 1 1)
					(thickness 0.15)
				)
				(justify mirror)
			)
		)
		(sheetname "2xSFP+")
		(sheetfile "2xSFP+.kicad_sch")
		(attr smd)
		(fp_rect
			(start -0.925 0.47)
			(end 0.925 -0.47)
			(stroke
				(width 0.05)
				(type default)
			)
			(fill no)
			(layer "B.CrtYd")
		)
		(fp_line
			(start -0.494 -0.248)
			(end 0.504 -0.248)
			(stroke
				(width 0.15)
				(type solid)
			)
			(layer "B.Fab")
		)
		(fp_line
			(start -0.494 0.25)
			(end -0.494 -0.248)
			(stroke
				(width 0.15)
				(type solid)
			)
			(layer "B.Fab")
		)
		(fp_line
			(start 0.504 -0.248)
			(end 0.504 0.25)
			(stroke
				(width 0.15)
				(type solid)
			)
			(layer "B.Fab")
		)
		(fp_line
			(start 0.504 0.25)
			(end -0.494 0.25)
			(stroke
				(width 0.15)
				(type solid)
			)
			(layer "B.Fab")
		)
		(pad "1" smd roundrect
			(at -0.48 0)
			(size 0.59 0.64)
			(layers "B.Cu" "B.Mask" "B.Paste")
			(roundrect_rratio 0.25)
			(net 1 "GND")
			(pintype "passive")
			(teardrops
				(best_length_ratio 0.2)
				(max_length 1)
				(best_width_ratio 0.9)
				(max_width 2)
				(curved_edges yes)
				(filter_ratio 0.9)
				(enabled yes)
				(allow_two_segments yes)
				(prefer_zone_connections yes)
			)
		)
		(pad "2" smd roundrect
			(at 0.48 0)
			(size 0.59 0.64)
			(layers "B.Cu" "B.Mask" "B.Paste")
			(roundrect_rratio 0.25)
			(net 2 "+3V3")
			(pintype "passive")
			(teardrops
				(best_length_ratio 0.2)
				(max_length 1)
				(best_width_ratio 0.9)
				(max_width 2)
				(curved_edges yes)
				(filter_ratio 0.9)
				(enabled yes)
				(allow_two_segments yes)
				(prefer_zone_connections yes)
			)
		)
	)
	(footprint "antmicro-footprints:C_0402_1005Metric"
		(layer "B.Cu")
		(at 215.986207 126.054416 90)
		(descr "Capacitor SMD 0402")
		(tags "capacitor SMD 0402")
		(property "Reference" "C104"
			(at -3.655584 0.413793 90)
			(layer "B.SilkS")
			(effects
				(font
					(size 0.7 0.7)
					(thickness 0.15)
				)
				(justify right bottom mirror)
			)
		)
		(property "Value" "C_100n_0402"
			(at -1.022927 -2.155213 90)
			(layer "B.Fab")
			(effects
				(font
					(size 0.7 0.7)
					(thickness 0.15)
				)
				(justify right bottom mirror)
			)
		)
		(property "Datasheet" "https://www.murata.com/products/productdetail?partno=GRM155R61H104KE14%23"
			(at 0 0 90)
			(layer "F.Fab")
			(hide yes)
			(effects
				(font
					(size 1.27 1.27)
					(thickness 0.15)
				)
			)
		)
		(property "Author" "Antmicro"
			(at 342.040623 -89.931791 0)
			(layer "B.Fab")
			(hide yes)
			(effects
				(font
					(size 1 1)
					(thickness 0.15)
				)
				(justify mirror)
			)
		)
		(property "Dielectric" "X5R"
			(at 342.040623 -89.931791 0)
			(layer "B.Fab")
			(hide yes)
			(effects
				(font
					(size 1 1)
					(thickness 0.15)
				)
				(justify mirror)
			)
		)
		(property "License" "Apache-2.0"
			(at 342.040623 -89.931791 0)
			(layer "B.Fab")
			(hide yes)
			(effects
				(font
					(size 1 1)
					(thickness 0.15)
				)
				(justify mirror)
			)
		)
		(property "MPN" "GRM155R61H104KE14D"
			(at 342.040623 -89.931791 0)
			(layer "B.Fab")
			(hide yes)
			(effects
				(font
					(size 1 1)
					(thickness 0.15)
				)
				(justify mirror)
			)
		)
		(property "Manufacturer" "Murata"
			(at 342.040623 -89.931791 0)
			(layer "B.Fab")
			(hide yes)
			(effects
				(font
					(size 1 1)
					(thickness 0.15)
				)
				(justify mirror)
			)
		)
		(property "Public" "False"
			(at 342.040623 -89.931791 0)
			(layer "B.Fab")
			(hide yes)
			(effects
				(font
					(size 1 1)
					(thickness 0.15)
				)
				(justify mirror)
			)
		)
		(property "Val" "100n"
			(at 342.040623 -89.931791 0)
			(layer "B.Fab")
			(hide yes)
			(effects
				(font
					(size 1 1)
					(thickness 0.15)
				)
				(justify mirror)
			)
		)
		(property "Voltage" "50V"
			(at 342.040623 -89.931791 0)
			(layer "B.Fab")
			(hide yes)
			(effects
				(font
					(size 1 1)
					(thickness 0.15)
				)
				(justify mirror)
			)
		)
		(sheetname "PCIe misc")
		(sheetfile "pcie_misc.kicad_sch")
		(attr smd)
		(fp_rect
			(start -0.925 0.47)
			(end 0.925 -0.47)
			(stroke
				(width 0.05)
				(type default)
			)
			(fill no)
			(layer "B.CrtYd")
		)
		(fp_line
			(start 0.504 -0.248)
			(end 0.504 0.25)
			(stroke
				(width 0.15)
				(type solid)
			)
			(layer "B.Fab")
		)
		(fp_line
			(start -0.494 -0.248)
			(end 0.504 -0.248)
			(stroke
				(width 0.15)
				(type solid)
			)
			(layer "B.Fab")
		)
		(fp_line
			(start 0.504 0.25)
			(end -0.494 0.25)
			(stroke
				(width 0.15)
				(type solid)
			)
			(layer "B.Fab")
		)
		(fp_line
			(start -0.494 0.25)
			(end -0.494 -0.248)
			(stroke
				(width 0.15)
				(type solid)
			)
			(layer "B.Fab")
		)
		(pad "1" smd roundrect
			(at -0.48 0 90)
			(size 0.59 0.64)
			(layers "B.Cu" "B.Mask" "B.Paste")
			(roundrect_rratio 0.25)
			(net 1 "GND")
			(pintype "passive")
			(teardrops
				(best_length_ratio 0.2)
				(max_length 1)
				(best_width_ratio 0.9)
				(max_width 2)
				(curved_edges yes)
				(filter_ratio 0.9)
				(enabled yes)
				(allow_two_segments yes)
				(prefer_zone_connections yes)
			)
		)
		(pad "2" smd roundrect
			(at 0.48 0 90)
			(size 0.59 0.64)
			(layers "B.Cu" "B.Mask" "B.Paste")
			(roundrect_rratio 0.25)
			(net 2 "+3V3")
			(pintype "passive")
			(teardrops
				(best_length_ratio 0.2)
				(max_length 1)
				(best_width_ratio 0.9)
				(max_width 2)
				(curved_edges yes)
				(filter_ratio 0.9)
				(enabled yes)
				(allow_two_segments yes)
				(prefer_zone_connections yes)
			)
		)
	)
	(footprint "antmicro-footprints:R_0402_1005Metric"
		(layer "B.Cu")
		(at 100.25 95.51 180)
		(descr "Resistor SMD 0402")
		(tags "resistor SMD 0402")
		(property "Reference" "R11"
			(at -1.075 0.49 0)
			(layer "B.SilkS")
			(effects
				(font
					(size 0.7 0.7)
					(thickness 0.15)
				)
				(justify left bottom mirror)
			)
		)
		(property "Value" "R_330R_0402"
			(at -1.011843 -1.772047 0)
			(layer "B.Fab")
			(effects
				(font
					(size 0.7 0.7)
					(thickness 0.15)
				)
				(justify left bottom mirror)
			)
		)
		(property "Datasheet" "https://www.bourns.com/docs/product-datasheets/cr.pdf"
			(at 0 0 180)
			(layer "F.Fab")
			(hide yes)
			(effects
				(font
					(size 1.27 1.27)
					(thickness 0.15)
				)
			)
		)
		(property "Author" "Antmicro"
			(at 200.5 191.02 0)
			(layer "B.Fab")
			(hide yes)
			(effects
				(font
					(size 1 1)
					(thickness 0.15)
				)
				(justify mirror)
			)
		)
		(property "License" "Apache-2.0"
			(at 200.5 191.02 0)
			(layer "B.Fab")
			(hide yes)
			(effects
				(font
					(size 1 1)
					(thickness 0.15)
				)
				(justify mirror)
			)
		)
		(property "MPN" "CR0402-FX-3300GLF"
			(at 200.5 191.02 0)
			(layer "B.Fab")
			(hide yes)
			(effects
				(font
					(size 1 1)
					(thickness 0.15)
				)
				(justify mirror)
			)
		)
		(property "Manufacturer" "Bourns"
			(at 200.5 191.02 0)
			(layer "B.Fab")
			(hide yes)
			(effects
				(font
					(size 1 1)
					(thickness 0.15)
				)
				(justify mirror)
			)
		)
		(property "Public" "False"
			(at 200.5 191.02 0)
			(layer "B.Fab")
			(hide yes)
			(effects
				(font
					(size 1 1)
					(thickness 0.15)
				)
				(justify mirror)
			)
		)
		(property "Tolerance" "1%"
			(at 200.5 191.02 0)
			(layer "B.Fab")
			(hide yes)
			(effects
				(font
					(size 1 1)
					(thickness 0.15)
				)
				(justify mirror)
			)
		)
		(property "Val" "330R"
			(at 200.5 191.02 0)
			(layer "B.Fab")
			(hide yes)
			(effects
				(font
					(size 1 1)
					(thickness 0.15)
				)
				(justify mirror)
			)
		)
		(sheetname "2xUSB3.0+RJ45")
		(sheetfile "usb3+rj45.kicad_sch")
		(attr smd)
		(fp_rect
			(start -0.925 0.47)
			(end 0.925 -0.47)
			(stroke
				(width 0.05)
				(type default)
			)
			(fill no)
			(layer "B.CrtYd")
		)
		(fp_rect
			(start -0.5 0.25)
			(end 0.5 -0.25)
			(stroke
				(width 0.15)
				(type solid)
			)
			(fill no)
			(layer "B.Fab")
		)
		(pad "1" smd roundrect
			(at -0.48 0 180)
			(size 0.59 0.64)
			(layers "B.Cu" "B.Mask" "B.Paste")
			(roundrect_rratio 0.25)
			(net 579 "/2xUSB3.0+RJ45/SH")
			(pintype "passive")
			(teardrops
				(best_length_ratio 0.2)
				(max_length 1)
				(best_width_ratio 0.9)
				(max_width 2)
				(curved_edges yes)
				(filter_ratio 0.9)
				(enabled yes)
				(allow_two_segments yes)
				(prefer_zone_connections yes)
			)
		)
		(pad "2" smd roundrect
			(at 0.48 0 180)
			(size 0.59 0.64)
			(layers "B.Cu" "B.Mask" "B.Paste")
			(roundrect_rratio 0.25)
			(net 1 "GND")
			(pintype "passive")
			(teardrops
				(best_length_ratio 0.2)
				(max_length 1)
				(best_width_ratio 0.9)
				(max_width 2)
				(curved_edges yes)
				(filter_ratio 0.9)
				(enabled yes)
				(allow_two_segments yes)
				(prefer_zone_connections yes)
			)
		)
	)
	(footprint "antmicro-footprints:R_0402_1005Metric"
		(layer "B.Cu")
		(at 128.79 136.06)
		(descr "Resistor SMD 0402")
		(tags "resistor SMD 0402")
		(property "Reference" "R300"
			(at -1.49 -0.5 0)
			(layer "B.SilkS")
			(effects
				(font
					(size 0.7 0.7)
					(thickness 0.15)
				)
				(justify right bottom mirror)
			)
		)
		(property "Value" "R_10k_0402"
			(at -1.011843 -1.772047 0)
			(layer "B.Fab")
			(effects
				(font
					(size 0.7 0.7)
					(thickness 0.15)
				)
				(justify right bottom mirror)
			)
		)
		(property "Datasheet" "https://www.bourns.com/docs/product-datasheets/cr.pdf"
			(at 0 0 0)
			(layer "F.Fab")
			(hide yes)
			(effects
				(font
					(size 1.27 1.27)
					(thickness 0.15)
				)
			)
		)
		(property "Author" "Antmicro"
			(at 0 0 0)
			(layer "B.Fab")
			(hide yes)
			(effects
				(font
					(size 1 1)
					(thickness 0.15)
				)
				(justify mirror)
			)
		)
		(property "License" "Apache-2.0"
			(at 0 0 0)
			(layer "B.Fab")
			(hide yes)
			(effects
				(font
					(size 1 1)
					(thickness 0.15)
				)
				(justify mirror)
			)
		)
		(property "MPN" "CR0402-FX-1002GLF"
			(at 0 0 0)
			(layer "B.Fab")
			(hide yes)
			(effects
				(font
					(size 1 1)
					(thickness 0.15)
				)
				(justify mirror)
			)
		)
		(property "Manufacturer" "Bourns"
			(at 0 0 0)
			(layer "B.Fab")
			(hide yes)
			(effects
				(font
					(size 1 1)
					(thickness 0.15)
				)
				(justify mirror)
			)
		)
		(property "Public" "False"
			(at 0 0 0)
			(layer "B.Fab")
			(hide yes)
			(effects
				(font
					(size 1 1)
					(thickness 0.15)
				)
				(justify mirror)
			)
		)
		(property "Tolerance" "1%"
			(at 0 0 0)
			(layer "B.Fab")
			(hide yes)
			(effects
				(font
					(size 1 1)
					(thickness 0.15)
				)
				(justify mirror)
			)
		)
		(property "Val" "10k"
			(at 0 0 0)
			(layer "B.Fab")
			(hide yes)
			(effects
				(font
					(size 1 1)
					(thickness 0.15)
				)
				(justify mirror)
			)
		)
		(sheetname "KR to SFI #2")
		(sheetfile "kr_sfi.kicad_sch")
		(attr smd)
		(fp_rect
			(start -0.925 0.47)
			(end 0.925 -0.47)
			(stroke
				(width 0.05)
				(type default)
			)
			(fill no)
			(layer "B.CrtYd")
		)
		(fp_rect
			(start -0.5 0.25)
			(end 0.5 -0.25)
			(stroke
				(width 0.15)
				(type solid)
			)
			(fill no)
			(layer "B.Fab")
		)
		(pad "1" smd roundrect
			(at -0.48 0)
			(size 0.59 0.64)
			(layers "B.Cu" "B.Mask" "B.Paste")
			(roundrect_rratio 0.25)
			(net 1 "GND")
			(pintype "passive")
			(teardrops
				(best_length_ratio 0.2)
				(max_length 1)
				(best_width_ratio 0.9)
				(max_width 2)
				(curved_edges yes)
				(filter_ratio 0.9)
				(enabled yes)
				(allow_two_segments yes)
				(prefer_zone_connections yes)
			)
		)
		(pad "2" smd roundrect
			(at 0.48 0)
			(size 0.59 0.64)
			(layers "B.Cu" "B.Mask" "B.Paste")
			(roundrect_rratio 0.25)
			(net 680 "Net-(U45C-PRTAD3)")
			(pintype "passive")
			(teardrops
				(best_length_ratio 0.2)
				(max_length 1)
				(best_width_ratio 0.9)
				(max_width 2)
				(curved_edges yes)
				(filter_ratio 0.9)
				(enabled yes)
				(allow_two_segments yes)
				(prefer_zone_connections yes)
			)
		)
	)
	(footprint "antmicro-footprints:R_0402_1005Metric"
		(layer "B.Cu")
		(at 138.05 169.16 -90)
		(descr "Resistor SMD 0402")
		(tags "resistor SMD 0402")
		(property "Reference" "R59"
			(at -3.9 13.5 90)
			(layer "B.SilkS")
			(effects
				(font
					(size 0.7 0.7)
					(thickness 0.15)
				)
				(justify left bottom mirror)
			)
		)
		(property "Value" "R_0R_0402"
			(at -1.011843 -1.772047 90)
			(layer "B.Fab")
			(effects
				(font
					(size 0.7 0.7)
					(thickness 0.15)
				)
				(justify left bottom mirror)
			)
		)
		(property "Datasheet" "https://industrial.panasonic.com/cdbs/www-data/pdf/RDA0000/AOA0000C301.pdf"
			(at 0 0 270)
			(layer "F.Fab")
			(hide yes)
			(effects
				(font
					(size 1.27 1.27)
					(thickness 0.15)
				)
			)
		)
		(property "Author" "Antmicro"
			(at -31.11 307.21 0)
			(layer "B.Fab")
			(hide yes)
			(effects
				(font
					(size 1 1)
					(thickness 0.15)
				)
				(justify mirror)
			)
		)
		(property "Current" "1A"
			(at -31.11 307.21 0)
			(layer "B.Fab")
			(hide yes)
			(effects
				(font
					(size 1 1)
					(thickness 0.15)
				)
				(justify mirror)
			)
		)
		(property "License" "Apache-2.0"
			(at -31.11 307.21 0)
			(layer "B.Fab")
			(hide yes)
			(effects
				(font
					(size 1 1)
					(thickness 0.15)
				)
				(justify mirror)
			)
		)
		(property "MPN" "ERJ2GE0R00X"
			(at -31.11 307.21 0)
			(layer "B.Fab")
			(hide yes)
			(effects
				(font
					(size 1 1)
					(thickness 0.15)
				)
				(justify mirror)
			)
		)
		(property "Manufacturer" "Panasonic"
			(at -31.11 307.21 0)
			(layer "B.Fab")
			(hide yes)
			(effects
				(font
					(size 1 1)
					(thickness 0.15)
				)
				(justify mirror)
			)
		)
		(property "Public" "False"
			(at -31.11 307.21 0)
			(layer "B.Fab")
			(hide yes)
			(effects
				(font
					(size 1 1)
					(thickness 0.15)
				)
				(justify mirror)
			)
		)
		(property "Tolerance" ""
			(at -31.11 307.21 0)
			(layer "B.Fab")
			(hide yes)
			(effects
				(font
					(size 1 1)
					(thickness 0.15)
				)
				(justify mirror)
			)
		)
		(property "Val" "0R"
			(at -31.11 307.21 0)
			(layer "B.Fab")
			(hide yes)
			(effects
				(font
					(size 1 1)
					(thickness 0.15)
				)
				(justify mirror)
			)
		)
		(sheetname "2xSFP+")
		(sheetfile "2xSFP+.kicad_sch")
		(attr smd)
		(fp_rect
			(start -0.925 0.47)
			(end 0.925 -0.47)
			(stroke
				(width 0.05)
				(type default)
			)
			(fill no)
			(layer "B.CrtYd")
		)
		(fp_rect
			(start -0.5 0.25)
			(end 0.5 -0.25)
			(stroke
				(width 0.15)
				(type solid)
			)
			(fill no)
			(layer "B.Fab")
		)
		(pad "1" smd roundrect
			(at -0.48 0 270)
			(size 0.59 0.64)
			(layers "B.Cu" "B.Mask" "B.Paste")
			(roundrect_rratio 0.25)
			(net 893 "Net-(J2B-TX_{DISABLE})")
			(pintype "passive")
			(teardrops
				(best_length_ratio 0.2)
				(max_length 1)
				(best_width_ratio 0.9)
				(max_width 2)
				(curved_edges yes)
				(filter_ratio 0.9)
				(enabled yes)
				(allow_two_segments yes)
				(prefer_zone_connections yes)
			)
		)
		(pad "2" smd roundrect
			(at 0.48 0 270)
			(size 0.59 0.64)
			(layers "B.Cu" "B.Mask" "B.Paste")
			(roundrect_rratio 0.25)
			(net 1 "GND")
			(pintype "passive")
			(teardrops
				(best_length_ratio 0.2)
				(max_length 1)
				(best_width_ratio 0.9)
				(max_width 2)
				(curved_edges yes)
				(filter_ratio 0.9)
				(enabled yes)
				(allow_two_segments yes)
				(prefer_zone_connections yes)
			)
		)
	)
	(footprint "antmicro-footprints:TP_SMD_0.75mm"
		(layer "B.Cu")
		(at 221.18 127.15)
		(property "Reference" "TP48"
			(at 0.37 0.46 0)
			(layer "B.SilkS")
			(effects
				(font
					(size 0.7 0.7)
					(thickness 0.15)
				)
				(justify right bottom mirror)
			)
		)
		(property "Value" "TP_0.75mm_SMD"
			(at 0 -1.2 0)
			(layer "B.Fab")
			(effects
				(font
					(size 0.7 0.7)
					(thickness 0.15)
				)
				(justify right bottom mirror)
			)
		)
		(property "Author" "Antmicro"
			(at 0 0 0)
			(layer "B.Fab")
			(hide yes)
			(effects
				(font
					(size 1 1)
					(thickness 0.15)
				)
				(justify mirror)
			)
		)
		(property "License" "Apache-2.0"
			(at 0 0 0)
			(layer "B.Fab")
			(hide yes)
			(effects
				(font
					(size 1 1)
					(thickness 0.15)
				)
				(justify mirror)
			)
		)
		(property "MPN" ""
			(at 0 0 0)
			(layer "B.Fab")
			(hide yes)
			(effects
				(font
					(size 1 1)
					(thickness 0.15)
				)
				(justify mirror)
			)
		)
		(property "Manufacturer" ""
			(at 0 0 0)
			(layer "B.Fab")
			(hide yes)
			(effects
				(font
					(size 1 1)
					(thickness 0.15)
				)
				(justify mirror)
			)
		)
		(property "Public" "False"
			(at 0 0 0)
			(layer "B.Fab")
			(hide yes)
			(effects
				(font
					(size 1 1)
					(thickness 0.15)
				)
				(justify mirror)
			)
		)
		(sheetname "PCIe misc")
		(sheetfile "pcie_misc.kicad_sch")
		(attr exclude_from_pos_files exclude_from_bom)
		(fp_circle
			(center 0 0)
			(end 0.475 0)
			(stroke
				(width 0.05)
				(type default)
			)
			(fill no)
			(layer "B.CrtYd")
		)
		(pad "1" smd circle
			(at 0 0)
			(size 0.75 0.75)
			(layers "B.Cu" "B.Mask")
			(net 622 "/PCIe misc/DIF5-")
			(pinfunction "1")
			(pintype "passive")
			(teardrops
				(best_length_ratio 0.4)
				(max_length 1)
				(best_width_ratio 0.9)
				(max_width 2)
				(curved_edges yes)
				(filter_ratio 0.9)
				(enabled yes)
				(allow_two_segments yes)
				(prefer_zone_connections yes)
			)
		)
	)
)
